(kicad_pcb
	(version 20260206)
	(generator "pcbnew")
	(generator_version "10.0")
	(general
		(thickness 1.6)
		(legacy_teardrops no)
	)
	(paper "A4")
	(title_block
		(title "01162023_DA0F0TEBIF0_F0T_Expander_BD_F_brd_V02_OCP.brd")
		(comment 1 "Grand Teton / footprints 2832-2837 of 9728")
	)
	(layers
		(0 "F.Cu" signal "TOP")
		(4 "In1.Cu" signal "GND")
		(6 "In2.Cu" signal "VCC")
		(8 "In3.Cu" signal "VCC1")
		(10 "In4.Cu" signal "GND1")
		(12 "In5.Cu" signal "IN1")
		(14 "In6.Cu" signal "GND2")
		(16 "In7.Cu" signal "IN2")
		(18 "In8.Cu" signal "GND3")
		(20 "In9.Cu" signal "IN3")
		(22 "In10.Cu" signal "GND4")
		(24 "In11.Cu" signal "IN4")
		(26 "In12.Cu" signal "GND5")
		(28 "In13.Cu" signal "IN5")
		(30 "In14.Cu" signal "GND6")
		(32 "In15.Cu" signal "IN6")
		(34 "In16.Cu" signal "GND7")
		(2 "B.Cu" signal "BOTTOM")
		(9 "F.Adhes" user "F.Adhesive")
		(11 "B.Adhes" user "B.Adhesive")
		(13 "F.Paste" user "Package Geometry/Pastemask Top")
		(15 "B.Paste" user "Package Geometry/Pastemask Bottom")
		(5 "F.SilkS" user "Ref Des/Silkscreen Top")
		(7 "B.SilkS" user "Ref Des/Silkscreen Bottom")
		(1 "F.Mask" user "Board Geometry/Soldermask Top")
		(3 "B.Mask" user "Board Geometry/Soldermask Bottom")
		(17 "Dwgs.User" user "User.Drawings")
		(19 "Cmts.User" user "User.Comments")
		(21 "Eco1.User" user "User.Eco1")
		(23 "Eco2.User" user "User.Eco2")
		(25 "Edge.Cuts" user "Board Geometry/Outline")
		(27 "Margin" user)
		(31 "F.CrtYd" user "Package Geometry/Place Bound Top")
		(29 "B.CrtYd" user "Package Geometry/Place Bound Bottom")
		(35 "F.Fab" user "Ref Des/Assembly Top")
		(33 "B.Fab" user "Ref Des/Assembly Bottom")
	)
	(footprint ""
		(layer "F.Cu")
		(at 224.022158 -77.563472 180)
		(property "Reference" "R4346"
			(at 0 0 180)
			(layer "F.SilkS")
			(hide yes)
			(effects
				(font
					(size 1.27 1.27)
				)
			)
		)
		(property "Value" ""
			(at 0 0 180)
			(layer "F.Fab")
			(effects
				(font
					(size 1.27 1.27)
				)
			)
		)
		(duplicate_pad_numbers_are_jumpers no)
		(fp_line
			(start 0.7874 0.4064)
			(end -0.7874 0.4064)
			(stroke
				(width 0.1524)
				(type default)
			)
			(layer "F.SilkS")
		)
		(fp_line
			(start 0.7874 -0.4064)
			(end 0.7874 0.4064)
			(stroke
				(width 0.1524)
				(type default)
			)
			(layer "F.SilkS")
		)
		(fp_line
			(start -0.7874 0.4064)
			(end -0.7874 -0.4064)
			(stroke
				(width 0.1524)
				(type default)
			)
			(layer "F.SilkS")
		)
		(fp_line
			(start -0.7874 -0.4064)
			(end 0.7874 -0.4064)
			(stroke
				(width 0.1524)
				(type default)
			)
			(layer "F.SilkS")
		)
		(fp_line
			(start 0.67945 0.3048)
			(end 0.120396 0.3048)
			(stroke
				(width 0.1)
				(type default)
			)
			(layer "F.Fab")
		)
		(fp_line
			(start 0.67945 -0.3048)
			(end 0.67945 0.3048)
			(stroke
				(width 0.1)
				(type default)
			)
			(layer "F.Fab")
		)
		(fp_line
			(start 0.12065 -0.2794)
			(end 0.12065 -0.3048)
			(stroke
				(width 0.1)
				(type default)
			)
			(layer "F.Fab")
		)
		(fp_line
			(start 0.12065 -0.3048)
			(end 0.67945 -0.3048)
			(stroke
				(width 0.1)
				(type default)
			)
			(layer "F.Fab")
		)
		(fp_line
			(start 0.120396 0.3048)
			(end 0.120396 0.2794)
			(stroke
				(width 0.1)
				(type default)
			)
			(layer "F.Fab")
		)
		(fp_line
			(start 0.120396 0.2794)
			(end -0.12065 0.2794)
			(stroke
				(width 0.1)
				(type default)
			)
			(layer "F.Fab")
		)
		(fp_line
			(start -0.12065 0.3048)
			(end -0.67945 0.3048)
			(stroke
				(width 0.1)
				(type default)
			)
			(layer "F.Fab")
		)
		(fp_line
			(start -0.12065 0.2794)
			(end -0.12065 0.3048)
			(stroke
				(width 0.1)
				(type default)
			)
			(layer "F.Fab")
		)
		(fp_line
			(start -0.12065 -0.2794)
			(end 0.12065 -0.2794)
			(stroke
				(width 0.1)
				(type default)
			)
			(layer "F.Fab")
		)
		(fp_line
			(start -0.12065 -0.305054)
			(end -0.12065 -0.2794)
			(stroke
				(width 0.1)
				(type default)
			)
			(layer "F.Fab")
		)
		(fp_line
			(start -0.67945 0.3048)
			(end -0.67945 -0.305054)
			(stroke
				(width 0.1)
				(type default)
			)
			(layer "F.Fab")
		)
		(fp_line
			(start -0.67945 -0.305054)
			(end -0.12065 -0.305054)
			(stroke
				(width 0.1)
				(type default)
			)
			(layer "F.Fab")
		)
		(pad "1" smd circle
			(at -0.40005 0 180)
			(size 0 0)
			(layers "F.Cu" "F.Mask" "F.Paste")
			(net "P3V3_AUX")
		)
		(pad "2" smd circle
			(at 0.40005 0 180)
			(size 0 0)
			(layers "F.Cu" "F.Mask" "F.Paste")
			(net "SSD8_LED_R")
		)
	)
	(footprint ""
		(layer "F.Cu")
		(at 83.65617 -61.487812 180)
		(property "Reference" "R5847"
			(at 0 0 180)
			(layer "F.SilkS")
			(hide yes)
			(effects
				(font
					(size 1.27 1.27)
				)
			)
		)
		(property "Value" ""
			(at 0 0 180)
			(layer "F.Fab")
			(effects
				(font
					(size 1.27 1.27)
				)
			)
		)
		(duplicate_pad_numbers_are_jumpers no)
		(fp_line
			(start 0.7874 0.4064)
			(end -0.7874 0.4064)
			(stroke
				(width 0.1524)
				(type default)
			)
			(layer "F.SilkS")
		)
		(fp_line
			(start 0.7874 -0.4064)
			(end 0.7874 0.4064)
			(stroke
				(width 0.1524)
				(type default)
			)
			(layer "F.SilkS")
		)
		(fp_line
			(start -0.7874 0.4064)
			(end -0.7874 -0.4064)
			(stroke
				(width 0.1524)
				(type default)
			)
			(layer "F.SilkS")
		)
		(fp_line
			(start -0.7874 -0.4064)
			(end 0.7874 -0.4064)
			(stroke
				(width 0.1524)
				(type default)
			)
			(layer "F.SilkS")
		)
		(fp_line
			(start 0.67945 0.3048)
			(end 0.120396 0.3048)
			(stroke
				(width 0.1)
				(type default)
			)
			(layer "F.Fab")
		)
		(fp_line
			(start 0.67945 -0.3048)
			(end 0.67945 0.3048)
			(stroke
				(width 0.1)
				(type default)
			)
			(layer "F.Fab")
		)
		(fp_line
			(start 0.12065 -0.2794)
			(end 0.12065 -0.3048)
			(stroke
				(width 0.1)
				(type default)
			)
			(layer "F.Fab")
		)
		(fp_line
			(start 0.12065 -0.3048)
			(end 0.67945 -0.3048)
			(stroke
				(width 0.1)
				(type default)
			)
			(layer "F.Fab")
		)
		(fp_line
			(start 0.120396 0.3048)
			(end 0.120396 0.2794)
			(stroke
				(width 0.1)
				(type default)
			)
			(layer "F.Fab")
		)
		(fp_line
			(start 0.120396 0.2794)
			(end -0.12065 0.2794)
			(stroke
				(width 0.1)
				(type default)
			)
			(layer "F.Fab")
		)
		(fp_line
			(start -0.12065 0.3048)
			(end -0.67945 0.3048)
			(stroke
				(width 0.1)
				(type default)
			)
			(layer "F.Fab")
		)
		(fp_line
			(start -0.12065 0.2794)
			(end -0.12065 0.3048)
			(stroke
				(width 0.1)
				(type default)
			)
			(layer "F.Fab")
		)
		(fp_line
			(start -0.12065 -0.2794)
			(end 0.12065 -0.2794)
			(stroke
				(width 0.1)
				(type default)
			)
			(layer "F.Fab")
		)
		(fp_line
			(start -0.12065 -0.305054)
			(end -0.12065 -0.2794)
			(stroke
				(width 0.1)
				(type default)
			)
			(layer "F.Fab")
		)
		(fp_line
			(start -0.67945 0.3048)
			(end -0.67945 -0.305054)
			(stroke
				(width 0.1)
				(type default)
			)
			(layer "F.Fab")
		)
		(fp_line
			(start -0.67945 -0.305054)
			(end -0.12065 -0.305054)
			(stroke
				(width 0.1)
				(type default)
			)
			(layer "F.Fab")
		)
		(pad "1" smd circle
			(at -0.40005 0 180)
			(size 0 0)
			(layers "F.Cu" "F.Mask" "F.Paste")
			(net "P3V3_AUX")
		)
		(pad "2" smd circle
			(at 0.40005 0 180)
			(size 0 0)
			(layers "F.Cu" "F.Mask" "F.Paste")
			(net "PWRGD_P12V_SSD3_D")
		)
	)
	(footprint ""
		(layer "F.Cu")
		(at 324.483222 -113.628678)
		(property "Reference" "PC898"
			(at 0 0 0)
			(layer "F.SilkS")
			(hide yes)
			(effects
				(font
					(size 1.27 1.27)
				)
			)
		)
		(property "Value" ""
			(at 0 0 0)
			(layer "F.Fab")
			(effects
				(font
					(size 1.27 1.27)
				)
			)
		)
		(duplicate_pad_numbers_are_jumpers no)
		(fp_line
			(start -0.7874 -0.4064)
			(end 0.7874 -0.4064)
			(stroke
				(width 0.1524)
				(type default)
			)
			(layer "F.SilkS")
		)
		(fp_line
			(start -0.7874 0.4064)
			(end -0.7874 -0.4064)
			(stroke
				(width 0.1524)
				(type default)
			)
			(layer "F.SilkS")
		)
		(fp_line
			(start 0.7874 -0.4064)
			(end 0.7874 0.4064)
			(stroke
				(width 0.1524)
				(type default)
			)
			(layer "F.SilkS")
		)
		(fp_line
			(start 0.7874 0.4064)
			(end -0.7874 0.4064)
			(stroke
				(width 0.1524)
				(type default)
			)
			(layer "F.SilkS")
		)
		(fp_line
			(start -0.67945 -0.305054)
			(end -0.12065 -0.305054)
			(stroke
				(width 0.1)
				(type default)
			)
			(layer "F.Fab")
		)
		(fp_line
			(start -0.67945 0.3048)
			(end -0.67945 -0.305054)
			(stroke
				(width 0.1)
				(type default)
			)
			(layer "F.Fab")
		)
		(fp_line
			(start -0.12065 -0.305054)
			(end -0.12065 -0.2794)
			(stroke
				(width 0.1)
				(type default)
			)
			(layer "F.Fab")
		)
		(fp_line
			(start -0.12065 -0.2794)
			(end 0.12065 -0.2794)
			(stroke
				(width 0.1)
				(type default)
			)
			(layer "F.Fab")
		)
		(fp_line
			(start -0.12065 0.2794)
			(end -0.12065 0.3048)
			(stroke
				(width 0.1)
				(type default)
			)
			(layer "F.Fab")
		)
		(fp_line
			(start -0.12065 0.3048)
			(end -0.67945 0.3048)
			(stroke
				(width 0.1)
				(type default)
			)
			(layer "F.Fab")
		)
		(fp_line
			(start 0.120396 0.2794)
			(end -0.12065 0.2794)
			(stroke
				(width 0.1)
				(type default)
			)
			(layer "F.Fab")
		)
		(fp_line
			(start 0.120396 0.3048)
			(end 0.120396 0.2794)
			(stroke
				(width 0.1)
				(type default)
			)
			(layer "F.Fab")
		)
		(fp_line
			(start 0.12065 -0.3048)
			(end 0.67945 -0.3048)
			(stroke
				(width 0.1)
				(type default)
			)
			(layer "F.Fab")
		)
		(fp_line
			(start 0.12065 -0.2794)
			(end 0.12065 -0.3048)
			(stroke
				(width 0.1)
				(type default)
			)
			(layer "F.Fab")
		)
		(fp_line
			(start 0.67945 -0.3048)
			(end 0.67945 0.3048)
			(stroke
				(width 0.1)
				(type default)
			)
			(layer "F.Fab")
		)
		(fp_line
			(start 0.67945 0.3048)
			(end 0.120396 0.3048)
			(stroke
				(width 0.1)
				(type default)
			)
			(layer "F.Fab")
		)
		(pad "1" smd circle
			(at -0.40005 0)
			(size 0 0)
			(layers "F.Cu" "F.Mask" "F.Paste")
			(net "P3V3_AUX")
		)
		(pad "2" smd circle
			(at 0.40005 0)
			(size 0 0)
			(layers "F.Cu" "F.Mask" "F.Paste")
			(net "GND")
		)
	)
	(footprint ""
		(layer "F.Cu")
		(at 119.0879 -293.816786 -90)
		(property "Reference" "PC100"
			(at 0 0 270)
			(layer "F.SilkS")
			(hide yes)
			(effects
				(font
					(size 1.27 1.27)
				)
			)
		)
		(property "Value" ""
			(at 0 0 270)
			(layer "F.Fab")
			(effects
				(font
					(size 1.27 1.27)
				)
			)
		)
		(duplicate_pad_numbers_are_jumpers no)
		(fp_line
			(start -0.7874 0.4064)
			(end -0.7874 -0.4064)
			(stroke
				(width 0.1524)
				(type default)
			)
			(layer "F.SilkS")
		)
		(fp_line
			(start 0.7874 0.4064)
			(end -0.7874 0.4064)
			(stroke
				(width 0.1524)
				(type default)
			)
			(layer "F.SilkS")
		)
		(fp_line
			(start -0.7874 -0.4064)
			(end 0.7874 -0.4064)
			(stroke
				(width 0.1524)
				(type default)
			)
			(layer "F.SilkS")
		)
		(fp_line
			(start 0.7874 -0.4064)
			(end 0.7874 0.4064)
			(stroke
				(width 0.1524)
				(type default)
			)
			(layer "F.SilkS")
		)
		(fp_line
			(start -0.67945 0.3048)
			(end -0.67945 -0.305054)
			(stroke
				(width 0.1)
				(type default)
			)
			(layer "F.Fab")
		)
		(fp_line
			(start -0.12065 0.3048)
			(end -0.67945 0.3048)
			(stroke
				(width 0.1)
				(type default)
			)
			(layer "F.Fab")
		)
		(fp_line
			(start 0.120396 0.3048)
			(end 0.120396 0.2794)
			(stroke
				(width 0.1)
				(type default)
			)
			(layer "F.Fab")
		)
		(fp_line
			(start 0.67945 0.3048)
			(end 0.120396 0.3048)
			(stroke
				(width 0.1)
				(type default)
			)
			(layer "F.Fab")
		)
		(fp_line
			(start -0.12065 0.2794)
			(end -0.12065 0.3048)
			(stroke
				(width 0.1)
				(type default)
			)
			(layer "F.Fab")
		)
		(fp_line
			(start 0.120396 0.2794)
			(end -0.12065 0.2794)
			(stroke
				(width 0.1)
				(type default)
			)
			(layer "F.Fab")
		)
		(fp_line
			(start -0.12065 -0.2794)
			(end 0.12065 -0.2794)
			(stroke
				(width 0.1)
				(type default)
			)
			(layer "F.Fab")
		)
		(fp_line
			(start 0.12065 -0.2794)
			(end 0.12065 -0.3048)
			(stroke
				(width 0.1)
				(type default)
			)
			(layer "F.Fab")
		)
		(fp_line
			(start 0.12065 -0.3048)
			(end 0.67945 -0.3048)
			(stroke
				(width 0.1)
				(type default)
			)
			(layer "F.Fab")
		)
		(fp_line
			(start 0.67945 -0.3048)
			(end 0.67945 0.3048)
			(stroke
				(width 0.1)
				(type default)
			)
			(layer "F.Fab")
		)
		(fp_line
			(start -0.67945 -0.305054)
			(end -0.12065 -0.305054)
			(stroke
				(width 0.1)
				(type default)
			)
			(layer "F.Fab")
		)
		(fp_line
			(start -0.12065 -0.305054)
			(end -0.12065 -0.2794)
			(stroke
				(width 0.1)
				(type default)
			)
			(layer "F.Fab")
		)
		(pad "1" smd circle
			(at -0.40005 0 270)
			(size 0 0)
			(layers "F.Cu" "F.Mask" "F.Paste")
			(net "P0V8_PEX1")
		)
		(pad "2" smd circle
			(at 0.40005 0 270)
			(size 0 0)
			(layers "F.Cu" "F.Mask" "F.Paste")
			(net "GND")
		)
	)
	(footprint ""
		(layer "F.Cu")
		(at 183.923432 -343.952322 90)
		(property "Reference" "C2532"
			(at 0 0 90)
			(layer "F.SilkS")
			(hide yes)
			(effects
				(font
					(size 1.27 1.27)
				)
			)
		)
		(property "Value" ""
			(at 0 0 90)
			(layer "F.Fab")
			(effects
				(font
					(size 1.27 1.27)
				)
			)
		)
		(duplicate_pad_numbers_are_jumpers no)
		(fp_line
			(start 0.299974 -0.150114)
			(end 0.299974 0.150114)
			(stroke
				(width 0.1)
				(type default)
			)
			(layer "F.Fab")
		)
		(fp_line
			(start -0.299974 -0.150114)
			(end 0.299974 -0.150114)
			(stroke
				(width 0.1)
				(type default)
			)
			(layer "F.Fab")
		)
		(fp_line
			(start 0.299974 0.150114)
			(end -0.299974 0.150114)
			(stroke
				(width 0.1)
				(type default)
			)
			(layer "F.Fab")
		)
		(fp_line
			(start -0.299974 0.150114)
			(end -0.299974 -0.150114)
			(stroke
				(width 0.1)
				(type default)
			)
			(layer "F.Fab")
		)
		(pad "1" smd rect
			(at -0.2667 0 90)
			(size 0.3048 0.381)
			(layers "F.Cu" "F.Mask" "F.Paste")
			(net "P5E_PEX1_STN4_TX_DP<69>")
		)
		(pad "2" smd rect
			(at 0.2667 0 90)
			(size 0.3048 0.381)
			(layers "F.Cu" "F.Mask" "F.Paste")
			(net "P5E_PEX1_STN4_TX_C_DP<69>")
		)
	)
	(footprint ""
		(layer "F.Cu")
		(at 322.959222 -235.075222 90)
		(property "Reference" "R4390"
			(at 0 0 90)
			(layer "F.SilkS")
			(hide yes)
			(effects
				(font
					(size 1.27 1.27)
				)
			)
		)
		(property "Value" ""
			(at 0 0 90)
			(layer "F.Fab")
			(effects
				(font
					(size 1.27 1.27)
				)
			)
		)
		(duplicate_pad_numbers_are_jumpers no)
		(fp_line
			(start 0.7874 -0.4064)
			(end 0.7874 0.4064)
			(stroke
				(width 0.1524)
				(type default)
			)
			(layer "F.SilkS")
		)
		(fp_line
			(start -0.7874 -0.4064)
			(end 0.7874 -0.4064)
			(stroke
				(width 0.1524)
				(type default)
			)
			(layer "F.SilkS")
		)
		(fp_line
			(start 0.7874 0.4064)
			(end -0.7874 0.4064)
			(stroke
				(width 0.1524)
				(type default)
			)
			(layer "F.SilkS")
		)
		(fp_line
			(start -0.7874 0.4064)
			(end -0.7874 -0.4064)
			(stroke
				(width 0.1524)
				(type default)
			)
			(layer "F.SilkS")
		)
		(fp_line
			(start -0.12065 -0.305054)
			(end -0.12065 -0.2794)
			(stroke
				(width 0.1)
				(type default)
			)
			(layer "F.Fab")
		)
		(fp_line
			(start -0.67945 -0.305054)
			(end -0.12065 -0.305054)
			(stroke
				(width 0.1)
				(type default)
			)
			(layer "F.Fab")
		)
		(fp_line
			(start 0.67945 -0.3048)
			(end 0.67945 0.3048)
			(stroke
				(width 0.1)
				(type default)
			)
			(layer "F.Fab")
		)
		(fp_line
			(start 0.12065 -0.3048)
			(end 0.67945 -0.3048)
			(stroke
				(width 0.1)
				(type default)
			)
			(layer "F.Fab")
		)
		(fp_line
			(start 0.12065 -0.2794)
			(end 0.12065 -0.3048)
			(stroke
				(width 0.1)
				(type default)
			)
			(layer "F.Fab")
		)
		(fp_line
			(start -0.12065 -0.2794)
			(end 0.12065 -0.2794)
			(stroke
				(width 0.1)
				(type default)
			)
			(layer "F.Fab")
		)
		(fp_line
			(start 0.120396 0.2794)
			(end -0.12065 0.2794)
			(stroke
				(width 0.1)
				(type default)
			)
			(layer "F.Fab")
		)
		(fp_line
			(start -0.12065 0.2794)
			(end -0.12065 0.3048)
			(stroke
				(width 0.1)
				(type default)
			)
			(layer "F.Fab")
		)
		(fp_line
			(start 0.67945 0.3048)
			(end 0.120396 0.3048)
			(stroke
				(width 0.1)
				(type default)
			)
			(layer "F.Fab")
		)
		(fp_line
			(start 0.120396 0.3048)
			(end 0.120396 0.2794)
			(stroke
				(width 0.1)
				(type default)
			)
			(layer "F.Fab")
		)
		(fp_line
			(start -0.12065 0.3048)
			(end -0.67945 0.3048)
			(stroke
				(width 0.1)
				(type default)
			)
			(layer "F.Fab")
		)
		(fp_line
			(start -0.67945 0.3048)
			(end -0.67945 -0.305054)
			(stroke
				(width 0.1)
				(type default)
			)
			(layer "F.Fab")
		)
		(pad "1" smd circle
			(at -0.40005 0 90)
			(size 0 0)
			(layers "F.Cu" "F.Mask" "F.Paste")
			(net "RST_PEX_SYS_BUF_R_N")
		)
		(pad "2" smd circle
			(at 0.40005 0 90)
			(size 0 0)
			(layers "F.Cu" "F.Mask" "F.Paste")
			(net "RST_PEX3_SYS_N")
		)
	)
)
